FILE_TYPE = CONNECTIVITY;
{Allegro Design Entry HDL 16.6-p007 (v16-6-112F) 10/10/2012}
"PAGE_NUMBER" = 199;
0"NC";
1"AGND_HSC\g";
2"AGND_HSC\g";
3"GND\g";
4"AGND_HSC\g";
5"AGND_HSC\g";
6"AGND_HSC\g";
7"GND\g";
8"AGND_HSC\g";
9"AGND_HSC\g";
10"AGND_HSC\g";
11"AGND_HSC\g";
12"GND\g";
13"GND\g";
14"AGND_HSC\g";
15"GND\g";
16"AGND_HSC\g";
17"AGND_HSC\g";
18"AGND_HSC\g";
19"GND\g";
20"AGND_HSC\g";
21"AGND_HSC\g";
22"AGND_HSC\g";
23"P12V_STBY\g";
24"P12V_STBY\g";
25"P12V_STBY\g";
26"P12V_PSU\g";
27"AGND_HSC\g";
28"AGND_HSC\g";
29"P12V_PSU\g";
30"A_HSC_OV";
31"A_HSC_UV";
32"P12V_HSC_VCC"VOLTAGE"+12V";
33"A_HSC_VCAP";
34"A_HSC_PSET";
35"A_HSC_ISTART";
36"A_HSC_TIMER";
37"PD_HSC_RETRY_N";
38"SMB_3V3SB_HSC_SDA_R";
39"A_HSC_MON";
40"FM_P12V_HSC_ADR1";
41"FM_P12V_HSC_ADR2";
42"A_HSC_ISET";
43"PWRGD_P12V_R";
44"A_HSC_TEMP";
45"A_HSC_HSP";
46"IRQ_HSC_FAULT_N";
47"SMB_3V3SB_HSC_SCL_R";
48"FM_P12V_HOTSWAP0_EN";
49"A_HSC_PWGIN";
50"IRQ_HSC_FAULT_R_N";
51"A_HSC_ISET_S";
52"A_HSC_ISET_S2";
53"A_HSC_OCP_SEL";
54"A_HSC_LOW_EN";
55"A_HSC_HIGH_EN";
56"TP_HSC_SPISSN";
57"A_HSC_MOP";
58"A_HSC_HSN";
59"SMB_BMC_PMBUS_STBY_LVC3_SDA";
60"SMB_BMC_PMBUS_STBY_LVC3_SCL";
61"A_HSC_GATE";
62"TP_HSC_MDAT";
63"TP_HSC_MCLK";
64"IRQ_SML1_PMBUS_ALERT_N";
65"A_HSC_HIGH_EN";
66"TEMP_SENSOR_E";
67"TEMP_SENSOR_B";
68"PWRGD_P12V_HSC";
69"A_HSC_LOW_GATE";
70"A_HSC_VOUT";
71"A_HSC_CSOUT";
72"IRQ_SML1_PMBUS_ALERT_R_N";
73"TP_HSC_ALERT2_N";
74"IRQ_SML1_PMBUS_ALERT_R_N";
%"ADM1278"
"1","(-3250,2575)","0","mstr_controller","I10";
;
CDS_SEC"1"
LOCATION"EU1D2"
MATERIAL"IC"
PART_NUMBER"G99251-001"
ROOM"HOT_SWAP"
PACK_TYPE"SM"
SEC_TYPE"SM"
SEC"1"
CDS_LOCATION"EU1D2"
CDS_LIB"mstr_controller";
"PWRGD"
$PN"18"43;
"FAULT_N"
$PN"6"50;
"EP"
$PN"33"9;
"PGND"
$PN"23"3;
"GND"
$PN"22"16;
"VOUT"
$PN"20"70;
"GATE"
$PN"24"61;
"CSOUT"
$PN"19"71;
"MDAT"
$PN"11"62;
"MCLK"
$PN"10"63;
"GPO2_ALERT2_N"
$PN"14"73;
"GPO1_ALERT1_N_CONV"
$PN"13"72;
"MON"
$PN"26"39;
"MOP"
$PN"29"57;
"HSN"
$PN"27"58;
"HSP"
$PN"28"45;
"TEMP"
$PN"25"44;
"PWGIN"
$PN"21"49;
"SPISS_N"
$PN"9"56;
"ENABLE"
$PN"12"48;
"ADR2"
$PN"8"41;
"ADR1"
$PN"7"40;
"SDA"
$PN"15"38;
"TIMER"
$PN"5"36;
"SCL"
$PN"16"47;
"RETRY_N"
$PN"17"37;
"ISTART"
$PN"4"35;
"PSET"
$PN"1"34;
"ISET"
$PN"3"42;
"OV"
$PN"32"30;
"VCAP"
$PN"2"33;
"UV"
$PN"31"31;
"VCC"
$PN"30"32;
%"RES"
"2","(-5300,800)","0","mstr_discrete","I100";
;
CDS_SEC"1"
PART_NUMBER"G21796-133"
MATERIAL"CHIP"
TOLERANCE"1%"
PACK_TYPE"0402"
LOCATION"R1D40"
VALUE"40.2K"
WATTAGE"1/16W"
SEC_TYPE"0402"
SEC"1"
ROOM"HOT_SWAP"
CDS_LOCATION"R1D40"
CDS_LIB"mstr_discrete";
"A"
$PN"1"34;
"B"
$PN"2"1;
%"AGND0"
"1","(-5400,450)","0","mstr_symbols","I101";
;
HDL_POWER"AGND_HSC"
BODY_TYPE"PLUMBING"
VOLTAGE"0"
BOM_COST"MIO_VRD_MAIN"
CDS_LIB"mstr_symbols"
ROOM"VR_P3V3";
"A"1;
%"RES"
"2","(-5600,750)","0","mstr_discrete","I102";
;
CDS_SEC"1"
WATTAGE"1/16W"
TOLERANCE"1.0%"
MATERIAL"CHIP"
VALUE"16K"
LOCATION"R1D34"
PART_NUMBER"G21796-317"
PACK_TYPE"0402"
SEC"1"
SEC_TYPE"0402"
ROOM"HOT_SWAP"
CDS_LOCATION"R1D34"
CDS_LIB"mstr_discrete";
"A"
$PN"1"35;
"B"
$PN"2"1;
%"CAP_A"
"1","(-6150,850)","2","dev_discrete","I105";
;
CDS_SEC"1"
PART_NUMBER"A36096-030"
VOLTAGE"16V"
TOLERANCE"10%"
PACK_TYPE"0402V"
MATERIAL"X7R"
VALUE"0.1UF"
LOCATION"C9P15"
SEC_TYPE"0402V"
SEC"1"
ROOM"HOT_SWAP"
CDS_LIB"dev_discrete"
CDS_LOCATION"C9P15";
"B"
$PN"2"2;
"A"
$PN"1"42;
%"AGND0"
"1","(-6150,600)","0","mstr_symbols","I106";
;
HDL_POWER"AGND_HSC"
BODY_TYPE"PLUMBING"
BOM_COST"MIO_VRD_MAIN"
ROOM"VR_P3V3"
CDS_LIB"mstr_symbols"
VOLTAGE"0";
"A"2;
%"CAP_A"
"1","(-6075,3575)","2","dev_discrete","I107";
;
MATERIAL"X7R"
VALUE"0.1UF"
VOLTAGE"16V"
TOLERANCE"10%"
LOCATION"C1D26"
PACK_TYPE"0402V"
PART_NUMBER"A36096-030"
SEC"1"
SEC_TYPE"0402V"
CDS_SEC"1"
ROOM"HOT_SWAP"
CDS_LOCATION"C1D26"
CDS_LIB"dev_discrete";
"B"
$PN"2"8;
"A"
$PN"1"31;
%"RES"
"1","(-2050,925)","0","mstr_discrete","I108";
;
CDS_SEC"1"
VALUE"33.2"
LOCATION"R1D33"
PACK_TYPE"0402"
TOLERANCE"1%"
MATERIAL"CHIP"
WATTAGE"1/16W"
PART_NUMBER"G21796-074"
SEC_TYPE"0402"
SEC"1"
CDS_LIB"mstr_discrete"
CDS_LOCATION"R1D33";
"B"
$PN"2"68;
"A"
$PN"1"43;
%"RES"
"1","(-1700,3950)","0","mstr_discrete","I109";
;
CDS_SEC"1"
PACK_TYPE"0402"
PART_NUMBER"G21796-074"
TOLERANCE"1%"
LOCATION"R1D26"
VALUE"33.2"
WATTAGE"1/16W"
MATERIAL"CHIP"
SEC_TYPE"0402"
SEC"1"
CDS_LOCATION"R1D26"
CDS_LIB"mstr_discrete";
"B"
$PN"2"64;
"A"
$PN"1"74;
%"GND"
"1","(-2150,2275)","0","mstr_symbols","I11";
;
HDL_POWER"GND"
BODY_TYPE"PLUMBING"
CDS_LIB"mstr_symbols"
VOLTAGE"0"
SIZE"1B";
"A\NAC"3;
%"RES"
"1","(-2050,1375)","0","mstr_discrete","I110";
;
CDS_SEC"1"
MATERIAL"CHIP"
VALUE"33.2"
PART_NUMBER"G21796-074"
TOLERANCE"1%"
WATTAGE"1/16W"
PACK_TYPE"0402"
LOCATION"R1D30"
SEC"1"
SEC_TYPE"0402"
CDS_LOCATION"R1D30"
CDS_LIB"mstr_discrete";
"B"
$PN"2"46;
"A"
$PN"1"50;
%"AGND0"
"1","(-6600,-25)","0","mstr_symbols","I112";
;
HDL_POWER"AGND_HSC"
BODY_TYPE"PLUMBING"
VOLTAGE"0"
CDS_LIB"mstr_symbols"
BOM_COST"MIO_VRD_MAIN"
ROOM"VR_P3V3";
"A"4;
%"AGND0"
"1","(-7200,3250)","0","mstr_symbols","I113";
;
HDL_POWER"AGND_HSC"
BODY_TYPE"PLUMBING"
CDS_LIB"mstr_symbols"
ROOM"VR_P3V3"
VOLTAGE"0"
BOM_COST"MIO_VRD_MAIN";
"A"5;
%"AGND0"
"1","(-5525,3350)","0","mstr_symbols","I115";
;
HDL_POWER"AGND_HSC"
BODY_TYPE"PLUMBING"
CDS_LIB"mstr_symbols"
VOLTAGE"0"
BOM_COST"MIO_VRD_MAIN"
ROOM"VR_P3V3";
"A"6;
%"GND"
"1","(-5100,3400)","0","mstr_symbols","I116";
;
HDL_POWER"GND"
BODY_TYPE"PLUMBING"
VOLTAGE"0"
SIZE"1B"
CDS_LIB"mstr_symbols";
"A\NAC"7;
%"AGND0"
"1","(-6375,3275)","0","mstr_symbols","I117";
;
HDL_POWER"AGND_HSC"
BODY_TYPE"PLUMBING"
BOM_COST"MIO_VRD_MAIN"
CDS_LIB"mstr_symbols"
VOLTAGE"0"
ROOM"VR_P3V3";
"A"8;
%"AGND0"
"1","(-2375,2300)","0","mstr_symbols","I118";
;
HDL_POWER"AGND_HSC"
BODY_TYPE"PLUMBING"
ROOM"VR_P3V3"
CDS_LIB"mstr_symbols"
BOM_COST"MIO_VRD_MAIN"
VOLTAGE"0";
"A"9;
%"CAP"
"1","(-5650,2000)","0","mstr_discrete","I119";
;
CDS_SEC"1"
VOLTAGE"16V"
PACK_TYPE"0402"
TOLERANCE"10%"
MATERIAL"X6S"
LOCATION"C1D19"
PART_NUMBER"D97712-011"
VALUE"1.0UF"
SEC_TYPE"0402"
SEC"1"
CDS_LOCATION"C1D19"
ROOM"HOT_SWAP"
CDS_LIB"mstr_discrete";
"A"
$PN"1"33;
"B"
$PN"2"10;
%"RES"
"2","(-6500,4050)","0","mstr_discrete","I12";
;
CDS_SEC"1"
PART_NUMBER"G21796-010"
MATERIAL"CHIP"
WATTAGE"1/16W"
LOCATION"R9P29"
VALUE"100.0K"
TOLERANCE"1%"
PACK_TYPE"0402"
CDS_LIB"mstr_discrete"
SEC_TYPE"0402"
SEC"1"
CDS_LOCATION"R9P29"
ROOM"HOT_SWAP";
"A"
$PN"1"26;
"B"
$PN"2"31;
%"AGND0"
"1","(-5650,1800)","0","mstr_symbols","I120";
;
HDL_POWER"AGND_HSC"
BODY_TYPE"PLUMBING"
BOM_COST"MIO_VRD_MAIN"
VOLTAGE"0"
CDS_LIB"mstr_symbols"
ROOM"VR_P3V3";
"A"10;
%"CAP_A"
"1","(-5000,425)","2","dev_discrete","I121";
;
LOCATION"C1D21"
VOLTAGE"16V"
TOLERANCE"10%"
MATERIAL"X7R"
PACK_TYPE"0402V"
PART_NUMBER"A36096-030"
VALUE"0.1UF"
ROOM"HOT_SWAP"
CDS_LOCATION"C1D21"
CDS_SEC"1"
SEC_TYPE"0402V"
SEC"1"
CDS_LIB"dev_discrete";
"B"
$PN"2"11;
"A"
$PN"1"34;
%"AGND0"
"1","(-5000,100)","0","mstr_symbols","I122";
;
HDL_POWER"AGND_HSC"
BODY_TYPE"PLUMBING"
VOLTAGE"0"
CDS_LIB"mstr_symbols"
BOM_COST"MIO_VRD_MAIN"
ROOM"VR_P3V3";
"A"11;
%"GND"
"1","(-3350,-100)","0","mstr_symbols","I128";
;
HDL_POWER"GND"
BODY_TYPE"PLUMBING"
SIZE"1B"
VOLTAGE"0"
CDS_LIB"mstr_symbols";
"A\NAC"12;
%"RES"
"2","(-6500,3600)","0","mstr_discrete","I13";
;
CDS_SEC"1"
WATTAGE"1/16W"
TOLERANCE"1%"
PACK_TYPE"0402"
PART_NUMBER"G21796-220"
MATERIAL"CHIP"
VALUE"11K"
LOCATION"R1D42"
SEC_TYPE"0402"
SEC"1"
CDS_LOCATION"R1D42"
ROOM"HOT_SWAP"
CDS_LIB"mstr_discrete";
"A"
$PN"1"31;
"B"
$PN"2"8;
%"FET_N"
"8","(-3350,200)","0","mstr_discrete","I130";
;
CDS_SEC"1"
PART_NUMBER"C79254-001"
MATERIAL"FET"
LOCATION"Q1W5"
VALUE"2N7002"
PACK_TYPE"SOT23LF"
ROOM"HOT_SWAP"
SEC_TYPE"SOT23LF"
SEC"1"
CDS_LIB"mstr_discrete"
CDS_LOCATION"Q1W5";
"GATE"
$PN"1"65;
"DRN"
$PN"3"69;
"SRC"
$PN"2"12;
%"CLX-CONN3A-1-GP"
"1","(-7750,725)","0","w_hdl","I131";
;
CDS_SEC"1"
CDS_LOCATION"J1B4"
LOCATION"J1B4"
VALUE"CLX-CONN3A-1-GP"
CDS_LMAN_SYM_OUTLINE"-50,125,50,-125"
CDS_LIB"w_hdl"
PART_NUMBER"021.D0139.0103"
SEC_TYPE"CONN-G3"
SEC"1"
PACK_TYPE"CONN-G3";
"3"
$PN"3"54;
"2"
$PN"2"53;
"1"
$PN"1"55;
%"CAP"
"1","(-1500,1700)","2","mstr_discrete","I132";
;
CDS_SEC"1"
VALUE"1000PF"
VOLTAGE"50V"
PACK_TYPE"0402LF"
LOCATION"C1W16"
PART_NUMBER"A36096-046"
TOLERANCE"10%"
MATERIAL"X7R"
CDS_LIB"mstr_discrete"
SEC_TYPE"0402LF"
SEC"1"
ROOM"PVCCIN_CPU0_VR"
CDS_LOCATION"C1W16";
"A"
$PN"1"44;
"B"
$PN"2"13;
%"GND"
"1","(-1500,1450)","0","mstr_symbols","I133";
;
HDL_POWER"GND"
BODY_TYPE"PLUMBING"
VOLTAGE"0"
CDS_LIB"mstr_symbols"
SIZE"1B";
"A\NAC"13;
%"RES"
"1","(-1250,1850)","0","mstr_discrete","I134";
;
CDS_SEC"1"
TOLERANCE"5%"
VALUE"0.0"
LOCATION"R1W20"
PACK_TYPE"0402"
PART_NUMBER"G21497-005"
WATTAGE"1/16W"
MATERIAL"CHIP"
ROOM"CPU0"
SEC"1"
SEC_TYPE"0402"
CDS_LIB"mstr_discrete"
BOM_COST"PROC_SIDEBAND"
CDS_LOCATION"R1W20";
"B"
$PN"2"67;
"A"
$PN"1"44;
%"RES"
"1","(-1250,1550)","0","mstr_discrete","I135";
;
CDS_SEC"1"
LOCATION"R1W21"
VALUE"0.0"
TOLERANCE"5%"
PACK_TYPE"0402"
WATTAGE"1/16W"
MATERIAL"CHIP"
PART_NUMBER"G21497-005"
BOM_COST"PROC_SIDEBAND"
CDS_LIB"mstr_discrete"
SEC_TYPE"0402"
SEC"1"
ROOM"CPU0"
CDS_LOCATION"R1W21";
"B"
$PN"2"66;
"A"
$PN"1"13;
%"RES"
"2","(-8000,2950)","0","mstr_discrete","I137";
;
VALUE"4.75K"
LOCATION"R1D29"
MATERIAL"CHIP"
PART_NUMBER"G21796-072"
PACK_TYPE"0402"
TOLERANCE"1%"
WATTAGE"1/16W"
POP"NOPOP"
CDS_LOCATION"R1D29"
CDS_SEC"1"
SEC_TYPE"0402"
SEC"1"
ROOM"CPU0"
CDS_LIB"mstr_discrete";
"A"
$PN"1"33;
"B"
$PN"2"40;
%"RES"
"2","(-7200,4025)","0","mstr_discrete","I138";
;
CDS_SEC"1"
PACK_TYPE"0402"
MATERIAL"CHIP"
WATTAGE"1/16W"
VALUE"100.0K"
TOLERANCE"1%"
LOCATION"R9P28"
PART_NUMBER"G21796-010"
CDS_LOCATION"R9P28"
CDS_LIB"mstr_discrete"
SEC_TYPE"0402"
SEC"1"
ROOM"HOT_SWAP";
"A"
$PN"1"26;
"B"
$PN"2"30;
%"RES"
"2","(-6600,1550)","0","mstr_discrete","I15";
;
CDS_SEC"1"
PART_NUMBER"G21796-010"
WATTAGE"1/16W"
TOLERANCE"1%"
MATERIAL"CHIP"
PACK_TYPE"0402"
LOCATION"R1D37"
VALUE"100.0K"
SEC_TYPE"0402"
SEC"1"
CDS_LOCATION"R1D37"
NO_XNET_CONNECTION"1"
ROOM"HOT_SWAP"
CDS_LIB"mstr_discrete";
"A"
$PN"1"33;
"B"
$PN"2"42;
%"RES"
"2","(-5300,1500)","0","mstr_discrete","I16";
;
CDS_SEC"1"
MATERIAL"CHIP"
TOLERANCE"1%"
WATTAGE"1/16W"
VALUE"100.0K"
LOCATION"R1D39"
PACK_TYPE"0402"
PART_NUMBER"G21796-010"
ROOM"HOT_SWAP"
NO_XNET_CONNECTION"1"
CDS_LOCATION"R1D39"
SEC"1"
SEC_TYPE"0402"
CDS_LIB"mstr_discrete";
"A"
$PN"1"33;
"B"
$PN"2"34;
%"RES"
"2","(-5600,1500)","0","mstr_discrete","I17";
;
CDS_SEC"1"
MATERIAL"CHIP"
PART_NUMBER"G21796-010"
LOCATION"R1D32"
PACK_TYPE"0402"
VALUE"100.0K"
TOLERANCE"1%"
WATTAGE"1/16W"
SEC_TYPE"0402"
SEC"1"
NO_XNET_CONNECTION"1"
ROOM"HOT_SWAP"
CDS_LOCATION"R1D32"
CDS_LIB"mstr_discrete";
"A"
$PN"1"33;
"B"
$PN"2"35;
%"AGND0"
"1","(-1350,150)","0","mstr_symbols","I18";
;
HDL_POWER"AGND_HSC"
BODY_TYPE"PLUMBING"
VOLTAGE"0"
CDS_LIB"mstr_symbols"
BOM_COST"MIO_VRD_MAIN"
ROOM"VR_P3V3";
"A"14;
%"RES"
"1","(-1650,300)","0","mstr_discrete","I19";
;
CDS_SEC"1"
LOCATION"R1D41"
PART_NUMBER"G22179-004"
MATERIAL"CHIP"
TOLERANCE"5%"
PACK_TYPE"0805"
WATTAGE"1/8W"
VALUE"0.0"
CDS_LIB"mstr_discrete"
SEC_TYPE"0805"
SEC"1"
ROOM"HOT_SWAP"
CDS_LOCATION"R1D41";
"B"
$PN"2"14;
"A"
$PN"1"15;
%"RES"
"2","(-5525,4025)","0","mstr_discrete","I2";
;
CDS_SEC"1"
LOCATION"R9P30"
WATTAGE"1/10W"
PACK_TYPE"0603"
PART_NUMBER"G22026-041"
MATERIAL"CHIP"
VALUE"10.0"
TOLERANCE"1%"
SEC_TYPE"0603"
SEC"1"
CDS_LOCATION"R9P30"
ROOM"HOT_SWAP"
CDS_LIB"mstr_discrete";
"A"
$PN"1"26;
"B"
$PN"2"32;
%"GND"
"1","(-1950,150)","0","mstr_symbols","I20";
;
HDL_POWER"GND"
BODY_TYPE"PLUMBING"
CDS_LIB"mstr_symbols"
SIZE"1B"
VOLTAGE"0";
"A\NAC"15;
%"AGND0"
"1","(-2000,2375)","0","mstr_symbols","I21";
;
HDL_POWER"AGND_HSC"
BODY_TYPE"PLUMBING"
CDS_LIB"mstr_symbols"
ROOM"VR_P3V3"
BOM_COST"MIO_VRD_MAIN"
VOLTAGE"0";
"A"16;
%"AGND0"
"1","(-4725,625)","0","mstr_symbols","I23";
;
HDL_POWER"AGND_HSC"
BODY_TYPE"PLUMBING"
VOLTAGE"0"
CDS_LIB"mstr_symbols"
BOM_COST"MIO_VRD_MAIN"
ROOM"VR_P3V3";
"A"17;
%"CAP"
"1","(-4850,1500)","0","mstr_discrete","I24";
;
CDS_SEC"1"
TOLERANCE"10%"
VALUE"0.033UF"
MATERIAL"X7R"
VOLTAGE"50V"
LOCATION"C9P14"
PART_NUMBER"603269-064"
PACK_TYPE"0603LF"
CDS_LIB"mstr_discrete"
ROOM"HOT_SWAP"
CDS_LOCATION"C9P14"
SEC"1"
SEC_TYPE"0603LF";
"A"
$PN"1"36;
"B"
$PN"2"17;
%"RES"
"2","(-4625,1025)","0","mstr_discrete","I26";
;
CDS_SEC"1"
WATTAGE"1/16W"
MATERIAL"EMPTY"
LOCATION"R1D28"
VALUE"100.0"
TOLERANCE"1%"
PACK_TYPE"0402"
PART_NUMBER"G21796-017"
ROOM"HOT_SWAP"
SEC_TYPE"0402"
CDS_LOCATION"R1D28"
SEC"1"
CDS_LIB"mstr_discrete";
"A"
$PN"1"37;
"B"
$PN"2"17;
%"RES"
"1","(-5600,2725)","0","mstr_discrete","I27";
;
CDS_SEC"1"
MATERIAL"CHIP"
PART_NUMBER"G21497-005"
TOLERANCE"5%"
WATTAGE"1/16W"
VALUE"0.0"
PACK_TYPE"0402"
LOCATION"R1D24"
CDS_LOCATION"R1D24"
CDS_LIB"mstr_discrete"
SEC_TYPE"0402"
SEC"1"
ROOM"HOT_SWAP";
"B"
$PN"2"47;
"A"
$PN"1"60;
%"RES"
"1","(-5600,2675)","0","mstr_discrete","I28";
;
CDS_SEC"1"
PART_NUMBER"G21497-005"
PACK_TYPE"0402"
TOLERANCE"5%"
MATERIAL"CHIP"
WATTAGE"1/16W"
LOCATION"R1D25"
VALUE"0.0"
CDS_LOCATION"R1D25"
CDS_LIB"mstr_discrete"
SEC_TYPE"0402"
SEC"1"
ROOM"HOT_SWAP";
"B"
$PN"2"38;
"A"
$PN"1"59;
%"CAP"
"1","(-5525,3600)","0","mstr_discrete","I3";
;
CDS_SEC"1"
LOCATION"C1D25"
VALUE"1.0UF"
VOLTAGE"16V"
PART_NUMBER"D97712-011"
MATERIAL"X6S"
PACK_TYPE"0402"
TOLERANCE"10%"
SEC_TYPE"0402"
ROOM"HOT_SWAP"
CDS_LOCATION"C1D25"
SEC"1"
CDS_LIB"mstr_discrete";
"A"
$PN"1"32;
"B"
$PN"2"6;
%"RES"
"2","(-8000,2375)","0","mstr_discrete","I33";
;
CDS_SEC"1"
LOCATION"R9P17"
WATTAGE"1/16W"
PART_NUMBER"G21796-109"
MATERIAL"CHIP"
PACK_TYPE"0402"
VALUE"150.0K"
TOLERANCE"1%"
SEC"1"
SEC_TYPE"0402"
ROOM"HOT_SWAP"
CDS_LIB"mstr_discrete"
CDS_LOCATION"R9P17";
"A"
$PN"1"40;
"B"
$PN"2"18;
%"AGND0"
"1","(-7675,2075)","0","mstr_symbols","I34";
;
HDL_POWER"AGND_HSC"
ROOM"VR_P3V3"
BOM_COST"MIO_VRD_MAIN"
CDS_LIB"mstr_symbols"
VOLTAGE"0"
BODY_TYPE"PLUMBING";
"A"18;
%"RES"
"2","(-7675,2375)","0","mstr_discrete","I36";
;
CDS_SEC"1"
BOM_DS"NOPOP"
PART_NUMBER"G21497-005"
VALUE"0.0"
TOLERANCE"5%"
WATTAGE"1/16W"
MATERIAL"CHIP"
PACK_TYPE"0402"
LOCATION"R9P16"
SEC_TYPE"0402"
SEC"1"
CDS_LIB"mstr_discrete"
CDS_LOCATION"R9P16"
ROOM"HOT_SWAP";
"A"
$PN"1"41;
"B"
$PN"2"18;
%"RES"
"2","(-7675,2950)","0","mstr_discrete","I38";
;
CDS_SEC"1"
PART_NUMBER"G21796-072"
VALUE"4.75K"
LOCATION"R1D27"
TOLERANCE"1%"
PACK_TYPE"0402"
MATERIAL"EMPTY"
WATTAGE"1/16W"
CDS_LIB"mstr_discrete"
CDS_LOCATION"R1D27"
SEC_TYPE"0402"
SEC"1"
NO_XNET_CONNECTION"1"
ROOM"HOT_SWAP";
"A"
$PN"1"33;
"B"
$PN"2"41;
%"RES"
"2","(-3125,1075)","2","mstr_discrete","I41";
;
CDS_SEC"1"
TOLERANCE"1%"
PACK_TYPE"0402"
LOCATION"R9P18"
WATTAGE"1/16W"
MATERIAL"CHIP"
PART_NUMBER"G21796-107"
VALUE"15.0K"
SEC_TYPE"0402"
SEC"1"
BOM_COST"MIO_USB"
ROOM"HOT_SWAP"
CDS_LOCATION"R9P18"
CDS_LIB"mstr_discrete";
"A"
$PN"1"25;
"B"
$PN"2"43;
%"RES"
"2","(-2825,750)","2","mstr_discrete","I43";
;
CDS_SEC"1"
WATTAGE"1/16W"
PART_NUMBER"G21796-161"
LOCATION"R1D31"
VALUE"6.19K"
TOLERANCE"1%"
MATERIAL"CHIP"
PACK_TYPE"0402"
ROOM"HOT_SWAP"
SEC"1"
SEC_TYPE"0402"
CDS_LOCATION"R1D31"
CDS_LIB"mstr_discrete";
"A"
$PN"1"43;
"B"
$PN"2"19;
%"GND"
"1","(-2825,550)","0","mstr_symbols","I44";
;
HDL_POWER"GND"
BODY_TYPE"PLUMBING"
VOLTAGE"0"
SIZE"1B"
CDS_LIB"mstr_symbols";
"A\NAC"19;
%"AGND0"
"1","(-7025,1975)","0","mstr_symbols","I52";
;
HDL_POWER"AGND_HSC"
BODY_TYPE"PLUMBING"
VOLTAGE"0"
BOM_COST"MIO_VRD_MAIN"
CDS_LIB"mstr_symbols"
ROOM"VR_P3V3";
"A"20;
%"CAP_A"
"1","(-7025,2175)","2","dev_discrete","I53";
;
TOLERANCE"10%"
PART_NUMBER"A36096-030"
PACK_TYPE"0402V"
MATERIAL"X7R"
VALUE"0.1UF"
VOLTAGE"16V"
LOCATION"C1D11"
SEC"1"
SEC_TYPE"0402V"
CDS_SEC"1"
ROOM"HOT_SWAP"
CDS_LIB"dev_discrete"
CDS_LOCATION"C1D11";
"B"
$PN"2"20;
"A"
$PN"1"48;
%"RES"
"2","(-6725,2025)","0","mstr_discrete","I54";
;
CDS_SEC"1"
LOCATION"R9P23"
VALUE"100.0K"
WATTAGE"1/16W"
PART_NUMBER"G21796-010"
TOLERANCE"1%"
MATERIAL"CHIP"
PACK_TYPE"0402"
SEC"1"
SEC_TYPE"0402"
ROOM"HOT_SWAP"
CDS_LOCATION"R9P23"
CDS_LIB"mstr_discrete";
"A"
$PN"1"24;
"B"
$PN"2"49;
%"RES"
"2","(-6725,1725)","2","mstr_discrete","I55";
;
CDS_SEC"1"
WATTAGE"1/16W"
VALUE"12.1K"
TOLERANCE"1%"
LOCATION"R9P24"
PACK_TYPE"0402"
PART_NUMBER"G21796-089"
MATERIAL"CHIP"
SEC_TYPE"0402"
SEC"1"
BOM_COST"MIO_USB"
ROOM"HOT_SWAP"
CDS_LOCATION"R9P24"
CDS_LIB"mstr_discrete";
"A"
$PN"1"49;
"B"
$PN"2"21;
%"AGND0"
"1","(-6725,1525)","0","mstr_symbols","I56";
;
HDL_POWER"AGND_HSC"
BODY_TYPE"PLUMBING"
VOLTAGE"0"
CDS_LIB"mstr_symbols"
BOM_COST"MIO_VRD_MAIN"
ROOM"VR_P3V3";
"A"21;
%"NPN"
"1","(-525,1700)","0","mstr_discrete","I58";
;
CDS_SEC"1"
PACK_TYPE"SM"
LOCATION"Q1D3"
VALUE"MMBT3904"
MATERIAL"IC"
PART_NUMBER"C52245-001"
SEC_TYPE"SM"
SEC"1"
CDS_LOCATION"Q1D3"
ROOM"HOT_SWAP"
CDS_LIB"mstr_discrete";
"C"
$PN"3"67;
"E"
$PN"2"66;
"B"
$PN"1"67;
%"RES"
"2","(-400,3025)","0","mstr_discrete","I65";
;
CDS_SEC"1"
LOCATION"R1D36"
VALUE"1.00K"
TOLERANCE"1%"
WATTAGE"1/16W"
MATERIAL"CHIP"
PART_NUMBER"G21796-026"
PACK_TYPE"0402"
SEC_TYPE"0402"
BOM_COST"MIO_USB"
CDS_LOCATION"R1D36"
SEC"1"
ROOM"HOT_SWAP"
CDS_LIB"mstr_discrete";
"A"
$PN"1"23;
"B"
$PN"2"70;
%"CAP_A"
"1","(-400,2625)","0","dev_discrete","I67";
;
CDS_SEC"1"
VOLTAGE"16V"
LOCATION"C9P12"
VALUE"0.1UF"
TOLERANCE"10%"
MATERIAL"EMPTY"
PART_NUMBER"A36096-030"
PACK_TYPE"0402V"
SEC_TYPE"0402V"
SEC"1"
ROOM"HOT_SWAP"
CDS_LOCATION"C9P12"
CDS_LIB"dev_discrete";
"B"
$PN"2"22;
"A"
$PN"1"70;
%"AGND0"
"1","(-400,2400)","0","mstr_symbols","I68";
;
HDL_POWER"AGND_HSC"
BODY_TYPE"PLUMBING"
BOM_COST"MIO_VRD_MAIN"
VOLTAGE"0"
CDS_LIB"mstr_symbols"
ROOM"VR_P3V3";
"A"22;
%"CAP_A"
"1","(-6775,3575)","2","dev_discrete","I7";
;
PART_NUMBER"A36096-030"
LOCATION"C1D27"
VALUE"0.1UF"
PACK_TYPE"0402V"
VOLTAGE"16V"
TOLERANCE"10%"
MATERIAL"X7R"
CDS_LOCATION"C1D27"
ROOM"HOT_SWAP"
CDS_SEC"1"
SEC_TYPE"0402V"
SEC"1"
CDS_LIB"dev_discrete";
"B"
$PN"2"5;
"A"
$PN"1"30;
%"P12V_STBY"
"1","(-400,3600)","0","mstr_symbols","I75";
;
HDL_POWER"P12V_STBY"
BODY_TYPE"PLUMBING"
SIZE"1B"
CDS_LIB"mstr_symbols"
VOLTAGE"12.0V";
"G\NAC"23;
%"P12V_STBY"
"1","(-6725,2250)","0","mstr_symbols","I76";
;
HDL_POWER"P12V_STBY"
BODY_TYPE"PLUMBING"
CDS_LIB"mstr_symbols"
SIZE"1B"
VOLTAGE"12.0V";
"G\NAC"24;
%"P12V_STBY"
"1","(-3125,1275)","0","mstr_symbols","I77";
;
HDL_POWER"P12V_STBY"
BODY_TYPE"PLUMBING"
SIZE"1B"
CDS_LIB"mstr_symbols"
VOLTAGE"12.0V";
"G\NAC"25;
%"P12V_PSU"
"1","(-6675,4425)","0","mstr_symbols","I79";
;
HDL_POWER"P12V_PSU"
BODY_TYPE"PLUMBING"
ROOM"P2V5_LAN_AUX_VR"
CDS_LIB"mstr_symbols"
BOM_COST"NT_BASE_VRD"
VOLTAGE"12.0";
"G\NAC"26;
%"FET_N_DUAL"
"5","(-6600,400)","0","mstr_discrete","I82";
;
CDS_SEC"2"
VALUE"2N7002DW"
MATERIAL"FET"
PART_NUMBER"D24280-001"
LOCATION"Q1D1"
ROOM"HOT_SWAP"
SEC_TYPE"SMLF"
SEC"2"
PACK_TYPE"SMLF"
CDS_LOCATION"Q1D1"
CDS_LIB"mstr_discrete";
"GATE <SIZE -1..0>"
$PN"5"55;
"SOURCE <SIZE-1..0>"
$PN"4"4;
"DRAIN <SIZE -1..0>"
$PN"3"51;
%"AGND0"
"1","(-5875,-25)","0","mstr_symbols","I83";
;
HDL_POWER"AGND_HSC"
BODY_TYPE"PLUMBING"
VOLTAGE"0"
CDS_LIB"mstr_symbols"
BOM_COST"MIO_VRD_MAIN"
ROOM"VR_P3V3";
"A"27;
%"RES"
"1","(-6600,975)","1","mstr_discrete","I84";
;
CDS_SEC"1"
BOM_DS"64.68125.6DL"
TOLERANCE"1%"
VALUE"90.9K"
PART_NUMBER"G21796-058"
LOCATION"R1D13"
WATTAGE"1/16W"
PACK_TYPE"0402"
MATERIAL"CHIP"
ROOM"HOT_SWAP"
CDS_LIB"mstr_discrete"
CDS_LOCATION"R1D13"
SEC_TYPE"0402"
SEC"1"
NO_XNET_CONNECTION"1";
"B"
$PN"2"42;
"A"
$PN"1"51;
%"RES"
"2","(-5875,875)","0","mstr_discrete","I85";
;
CDS_SEC"1"
BOM_DS"64.57625.6DL"
TOLERANCE"1%"
VALUE"69.8K"
LOCATION"R1D16"
PACK_TYPE"0402"
PART_NUMBER"G21796-007"
MATERIAL"CHIP"
WATTAGE"1/16W"
ROOM"HOT_SWAP"
NO_XNET_CONNECTION"1"
SEC"1"
SEC_TYPE"0402"
CDS_LOCATION"R1D16"
CDS_LIB"mstr_discrete";
"A"
$PN"1"42;
"B"
$PN"2"52;
%"FET_N_DUAL"
"5","(-5875,275)","0","mstr_discrete","I86";
;
CDS_SEC"1"
LOCATION"Q1D1"
MATERIAL"FET"
VALUE"2N7002DW"
PART_NUMBER"D24280-001"
ROOM"HOT_SWAP"
CDS_LOCATION"Q1D1"
SEC"1"
SEC_TYPE"SMLF"
CDS_LIB"mstr_discrete"
PACK_TYPE"SMLF";
"GATE <SIZE -1..0>"
$PN"2"54;
"SOURCE <SIZE-1..0>"
$PN"1"27;
"DRAIN <SIZE -1..0>"
$PN"6"52;
%"RES"
"2","(-6950,-50)","0","mstr_discrete","I87";
;
CDS_SEC"1"
VALUE"100.0K"
TOLERANCE"1%"
PACK_TYPE"0402"
LOCATION"R1D18"
PART_NUMBER"G21796-010"
MATERIAL"CHIP"
WATTAGE"1/16W"
CDS_LIB"mstr_discrete"
SEC_TYPE"0402"
SEC"1"
CDS_LOCATION"R1D18"
ROOM"HOT_SWAP";
"A"
$PN"1"55;
"B"
$PN"2"28;
%"RES"
"2","(-6300,-50)","0","mstr_discrete","I88";
;
CDS_SEC"1"
LOCATION"R1D11"
VALUE"100.0K"
TOLERANCE"1%"
WATTAGE"1/16W"
MATERIAL"CHIP"
PART_NUMBER"G21796-010"
PACK_TYPE"0402"
SEC_TYPE"0402"
SEC"1"
CDS_LOCATION"R1D11"
ROOM"HOT_SWAP"
CDS_LIB"mstr_discrete";
"A"
$PN"1"54;
"B"
$PN"2"28;
%"AGND0"
"1","(-6300,-325)","0","mstr_symbols","I89";
;
HDL_POWER"AGND_HSC"
BODY_TYPE"PLUMBING"
ROOM"VR_P3V3"
CDS_LIB"mstr_symbols"
BOM_COST"MIO_VRD_MAIN"
VOLTAGE"0";
"A"28;
%"RES"
"2","(-7200,3625)","0","mstr_discrete","I9";
;
CDS_SEC"1"
PACK_TYPE"0402"
PART_NUMBER"G21796-177"
MATERIAL"CHIP"
TOLERANCE"1%"
VALUE"7.5K"
LOCATION"R1D43"
CONFIG"064.7501D.06DD"
WATTAGE"1/16W"
SEC_TYPE"0402"
SEC"1"
CDS_LOCATION"R1D43"
ROOM"HOT_SWAP"
CDS_LIB"mstr_discrete";
"A"
$PN"1"30;
"B"
$PN"2"5;
%"P12V_PSU"
"1","(-7300,950)","0","mstr_symbols","I90";
;
HDL_POWER"P12V_PSU"
BODY_TYPE"PLUMBING"
ROOM"P2V5_LAN_AUX_VR"
BOM_COST"NT_BASE_VRD"
VOLTAGE"12.0"
CDS_LIB"mstr_symbols";
"G\NAC"29;
%"RES"
"2","(-7300,750)","0","mstr_discrete","I92";
;
CDS_SEC"1"
LOCATION"R1D15"
WATTAGE"1/16W"
PART_NUMBER"G21796-010"
VALUE"100.0K"
TOLERANCE"1%"
PACK_TYPE"0402"
MATERIAL"CHIP"
ROOM"HOT_SWAP"
CDS_LOCATION"R1D15"
SEC"1"
SEC_TYPE"0402"
CDS_LIB"mstr_discrete";
"A"
$PN"1"29;
"B"
$PN"2"53;
%"ZENER"
"4","(-5100,3875)","0","mstr_discrete","I99";
;
CDS_SEC"1"
NEW_VALUE"14V"
LOCATION"VR1D1"
PACK_TYPE"SM"
MATERIAL"IC"
NEW_PN"083.01514.00AD"
VALUE"13V"
SEC_TYPE"SM"
CDS_LIB"mstr_discrete"
SEC"1"
CDS_LOCATION"VR1D1"
PART_NUMBER"H69095-001";
"C"
$PN"1"26;
"A"
$PN"2"7;
END.
